(kicad_pcb
	(version 20260206)
	(generator "pcbnew")
	(generator_version "10.0")
	(general
		(thickness 1.6)
		(legacy_teardrops no)
	)
	(paper "A4")
	(title_block
		(title "04192023_DAF0TMB3IC0_F0TG_MB_C_brd_V02_OCP.brd")
		(comment 1 "Grand Teton / footprints 5231-5237 of 8354")
	)
	(layers
		(0 "F.Cu" signal "TOP")
		(4 "In1.Cu" signal "GND")
		(6 "In2.Cu" signal "IN1")
		(8 "In3.Cu" signal "GND1")
		(10 "In4.Cu" signal "IN2")
		(12 "In5.Cu" signal "GND2")
		(14 "In6.Cu" signal "IN3")
		(16 "In7.Cu" signal "GND3")
		(18 "In8.Cu" signal "VCC")
		(20 "In9.Cu" signal "VCC1")
		(22 "In10.Cu" signal "GND4")
		(24 "In11.Cu" signal "IN4")
		(26 "In12.Cu" signal "GND5")
		(28 "In13.Cu" signal "IN5")
		(30 "In14.Cu" signal "GND6")
		(32 "In15.Cu" signal "IN6")
		(34 "In16.Cu" signal "GND7")
		(2 "B.Cu" signal "BOTTOM")
		(9 "F.Adhes" user "F.Adhesive")
		(11 "B.Adhes" user "B.Adhesive")
		(13 "F.Paste" user "Package Geometry/Pastemask Top")
		(15 "B.Paste" user "Package Geometry/Pastemask Bottom")
		(5 "F.SilkS" user "Ref Des/Silkscreen Top")
		(7 "B.SilkS" user "Ref Des/Silkscreen Bottom")
		(1 "F.Mask" user "Board Geometry/Soldermask Top")
		(3 "B.Mask" user "Board Geometry/Soldermask Bottom")
		(17 "Dwgs.User" user "User.Drawings")
		(19 "Cmts.User" user "User.Comments")
		(21 "Eco1.User" user "User.Eco1")
		(23 "Eco2.User" user "User.Eco2")
		(25 "Edge.Cuts" user "Board Geometry/Outline")
		(27 "Margin" user)
		(31 "F.CrtYd" user "Package Geometry/Place Bound Top")
		(29 "B.CrtYd" user "Package Geometry/Place Bound Bottom")
		(35 "F.Fab" user "Ref Des/Assembly Top")
		(33 "B.Fab" user "Ref Des/Assembly Bottom")
	)
	(footprint ""
		(layer "B.Cu")
		(at 295.402 -424.942 180)
		(property "Reference" "R834"
			(at 0 0 0)
			(layer "B.SilkS")
			(hide yes)
			(effects
				(font
					(size 1.27 1.27)
				)
				(justify mirror)
			)
		)
		(property "Value" ""
			(at 0 0 0)
			(layer "B.Fab")
			(effects
				(font
					(size 1.27 1.27)
				)
				(justify mirror)
			)
		)
		(duplicate_pad_numbers_are_jumpers no)
		(fp_line
			(start 0.32512 0.175006)
			(end 0.32512 -0.175006)
			(stroke
				(width 0.1)
				(type default)
			)
			(layer "B.Fab")
		)
		(fp_line
			(start 0.32512 -0.175006)
			(end -0.32512 -0.175006)
			(stroke
				(width 0.1)
				(type default)
			)
			(layer "B.Fab")
		)
		(fp_line
			(start -0.32512 0.175006)
			(end 0.32512 0.175006)
			(stroke
				(width 0.1)
				(type default)
			)
			(layer "B.Fab")
		)
		(fp_line
			(start -0.32512 -0.175006)
			(end -0.32512 0.175006)
			(stroke
				(width 0.1)
				(type default)
			)
			(layer "B.Fab")
		)
		(pad "1" smd rect
			(at 0.2667 0)
			(size 0.3048 0.381)
			(layers "B.Cu" "B.Mask" "B.Paste")
			(net "P1V8_CPU0_RT_1D")
		)
		(pad "2" smd rect
			(at -0.2667 0 180)
			(size 0.3048 0.381)
			(layers "B.Cu" "B.Mask" "B.Paste")
			(net "SMB_RT_CPU0_P0_ROM_R_SDA")
		)
	)
	(footprint ""
		(layer "B.Cu")
		(at 184.332372 -116.642896 -90)
		(property "Reference" "C1174"
			(at 0 0 90)
			(layer "B.SilkS")
			(hide yes)
			(effects
				(font
					(size 1.27 1.27)
				)
				(justify mirror)
			)
		)
		(property "Value" ""
			(at 0 0 90)
			(layer "B.Fab")
			(effects
				(font
					(size 1.27 1.27)
				)
				(justify mirror)
			)
		)
		(duplicate_pad_numbers_are_jumpers no)
		(fp_line
			(start -0.69215 0.2921)
			(end 0.69215 0.2921)
			(stroke
				(width 0.1524)
				(type default)
			)
			(layer "B.SilkS")
		)
		(fp_line
			(start 0.69215 0.2921)
			(end 0.69215 -0.2921)
			(stroke
				(width 0.1524)
				(type default)
			)
			(layer "B.SilkS")
		)
		(fp_line
			(start -0.69215 -0.2921)
			(end -0.69215 0.2921)
			(stroke
				(width 0.1524)
				(type default)
			)
			(layer "B.SilkS")
		)
		(fp_line
			(start 0.69215 -0.2921)
			(end -0.69215 -0.2921)
			(stroke
				(width 0.1524)
				(type default)
			)
			(layer "B.SilkS")
		)
		(fp_line
			(start -0.51435 0.2794)
			(end 0.51435 0.2794)
			(stroke
				(width 0.1)
				(type default)
			)
			(layer "B.Fab")
		)
		(fp_line
			(start 0.51435 0.2794)
			(end 0.51435 -0.2794)
			(stroke
				(width 0.1)
				(type default)
			)
			(layer "B.Fab")
		)
		(fp_line
			(start -0.51435 -0.2794)
			(end -0.51435 0.2794)
			(stroke
				(width 0.1)
				(type default)
			)
			(layer "B.Fab")
		)
		(fp_line
			(start 0.51435 -0.2794)
			(end -0.51435 -0.2794)
			(stroke
				(width 0.1)
				(type default)
			)
			(layer "B.Fab")
		)
		(pad "1" smd circle
			(at 0.40005 0 90)
			(size 0 0)
			(layers "B.Cu" "B.Mask" "B.Paste")
			(net "P3V3_AUX")
		)
		(pad "2" smd circle
			(at -0.40005 0 90)
			(size 0 0)
			(layers "B.Cu" "B.Mask" "B.Paste")
			(net "GND")
		)
		(zone
			(layer "B.Cu")
			(hatch none 0.5)
			(connect_pads
				(clearance 0)
			)
			(min_thickness 0.25)
			(keepout
				(tracks not_allowed)
				(vias allowed)
				(pads allowed)
				(copperpour not_allowed)
				(footprints allowed)
			)
			(placement
				(enabled no)
				(sheetname "")
			)
			(fill
				(thermal_gap 0.5)
				(thermal_bridge_width 0.5)
				(island_removal_mode 0)
			)
			(polygon
				(pts
					(xy 184.186576 -116.543836) (xy 184.186576 -116.743226) (xy 184.244742 -116.833396) (xy 184.420002 -116.833396)
					(xy 184.478422 -116.743226) (xy 184.478422 -116.543836) (xy 184.420256 -116.452396) (xy 184.244742 -116.452396)
				)
			)
		)
	)
	(footprint ""
		(layer "B.Cu")
		(at 74.55408 -4.251198 90)
		(property "Reference" "R3167"
			(at 0 0 90)
			(layer "B.SilkS")
			(hide yes)
			(effects
				(font
					(size 1.27 1.27)
				)
				(justify mirror)
			)
		)
		(property "Value" ""
			(at 0 0 90)
			(layer "B.Fab")
			(effects
				(font
					(size 1.27 1.27)
				)
				(justify mirror)
			)
		)
		(duplicate_pad_numbers_are_jumpers no)
		(fp_line
			(start 0.7874 -0.4064)
			(end -0.7874 -0.4064)
			(stroke
				(width 0.1524)
				(type default)
			)
			(layer "B.SilkS")
		)
		(fp_line
			(start -0.7874 -0.4064)
			(end -0.7874 0.4064)
			(stroke
				(width 0.1524)
				(type default)
			)
			(layer "B.SilkS")
		)
		(fp_line
			(start 0.7874 0.4064)
			(end 0.7874 -0.4064)
			(stroke
				(width 0.1524)
				(type default)
			)
			(layer "B.SilkS")
		)
		(fp_line
			(start -0.7874 0.4064)
			(end 0.7874 0.4064)
			(stroke
				(width 0.1524)
				(type default)
			)
			(layer "B.SilkS")
		)
		(fp_line
			(start 0.67945 -0.305054)
			(end 0.12065 -0.305054)
			(stroke
				(width 0.1)
				(type default)
			)
			(layer "B.Fab")
		)
		(fp_line
			(start 0.12065 -0.305054)
			(end 0.12065 -0.2794)
			(stroke
				(width 0.1)
				(type default)
			)
			(layer "B.Fab")
		)
		(fp_line
			(start -0.12065 -0.3048)
			(end -0.67945 -0.3048)
			(stroke
				(width 0.1)
				(type default)
			)
			(layer "B.Fab")
		)
		(fp_line
			(start -0.67945 -0.3048)
			(end -0.67945 0.3048)
			(stroke
				(width 0.1)
				(type default)
			)
			(layer "B.Fab")
		)
		(fp_line
			(start 0.12065 -0.2794)
			(end -0.12065 -0.2794)
			(stroke
				(width 0.1)
				(type default)
			)
			(layer "B.Fab")
		)
		(fp_line
			(start -0.12065 -0.2794)
			(end -0.12065 -0.3048)
			(stroke
				(width 0.1)
				(type default)
			)
			(layer "B.Fab")
		)
		(fp_line
			(start 0.12065 0.2794)
			(end 0.12065 0.3048)
			(stroke
				(width 0.1)
				(type default)
			)
			(layer "B.Fab")
		)
		(fp_line
			(start -0.120396 0.2794)
			(end 0.12065 0.2794)
			(stroke
				(width 0.1)
				(type default)
			)
			(layer "B.Fab")
		)
		(fp_line
			(start 0.67945 0.3048)
			(end 0.67945 -0.305054)
			(stroke
				(width 0.1)
				(type default)
			)
			(layer "B.Fab")
		)
		(fp_line
			(start 0.12065 0.3048)
			(end 0.67945 0.3048)
			(stroke
				(width 0.1)
				(type default)
			)
			(layer "B.Fab")
		)
		(fp_line
			(start -0.120396 0.3048)
			(end -0.120396 0.2794)
			(stroke
				(width 0.1)
				(type default)
			)
			(layer "B.Fab")
		)
		(fp_line
			(start -0.67945 0.3048)
			(end -0.120396 0.3048)
			(stroke
				(width 0.1)
				(type default)
			)
			(layer "B.Fab")
		)
		(pad "1" smd circle
			(at 0.40005 0 270)
			(size 0 0)
			(layers "B.Cu" "B.Mask" "B.Paste")
			(net "OCP_V3_2_ID1")
		)
		(pad "2" smd circle
			(at -0.40005 0 270)
			(size 0 0)
			(layers "B.Cu" "B.Mask" "B.Paste")
			(net "GND")
		)
	)
	(footprint ""
		(layer "B.Cu")
		(at 89.560146 -178.736244 90)
		(property "Reference" "PC267_2"
			(at 0 0 90)
			(layer "B.SilkS")
			(hide yes)
			(effects
				(font
					(size 1.27 1.27)
				)
				(justify mirror)
			)
		)
		(property "Value" ""
			(at 0 0 90)
			(layer "B.Fab")
			(effects
				(font
					(size 1.27 1.27)
				)
				(justify mirror)
			)
		)
		(duplicate_pad_numbers_are_jumpers no)
		(fp_line
			(start 1.524 -0.762)
			(end -1.524 -0.762)
			(stroke
				(width 0.1524)
				(type default)
			)
			(layer "B.SilkS")
		)
		(fp_line
			(start -1.524 -0.762)
			(end -1.524 0.762)
			(stroke
				(width 0.1524)
				(type default)
			)
			(layer "B.SilkS")
		)
		(fp_line
			(start 1.524 0.762)
			(end 1.524 -0.762)
			(stroke
				(width 0.1524)
				(type default)
			)
			(layer "B.SilkS")
		)
		(fp_line
			(start -1.524 0.762)
			(end 1.524 0.762)
			(stroke
				(width 0.1524)
				(type default)
			)
			(layer "B.SilkS")
		)
		(fp_line
			(start 1.1049 -0.724916)
			(end 1.1049 0.724916)
			(stroke
				(width 0.1)
				(type default)
			)
			(layer "B.Fab")
		)
		(fp_line
			(start -1.1049 -0.724916)
			(end 1.1049 -0.724916)
			(stroke
				(width 0.1)
				(type default)
			)
			(layer "B.Fab")
		)
		(fp_line
			(start 1.1049 0.724916)
			(end -1.1049 0.724916)
			(stroke
				(width 0.1)
				(type default)
			)
			(layer "B.Fab")
		)
		(fp_line
			(start -1.1049 0.724916)
			(end -1.1049 -0.724916)
			(stroke
				(width 0.1)
				(type default)
			)
			(layer "B.Fab")
		)
		(pad "1" smd rect
			(at 0.889 0 90)
			(size 1.016 1.27)
			(layers "B.Cu" "B.Mask" "B.Paste")
			(net "SW_P12V_AUX_PVDDCR_CPU0_P1_FLT")
		)
		(pad "2" smd rect
			(at -0.889 0 90)
			(size 1.016 1.27)
			(layers "B.Cu" "B.Mask" "B.Paste")
			(net "GND")
		)
	)
	(footprint ""
		(layer "B.Cu")
		(at 344.511884 -335.092294 90)
		(property "Reference" "PC138_5"
			(at 0 0 90)
			(layer "B.SilkS")
			(hide yes)
			(effects
				(font
					(size 1.27 1.27)
				)
				(justify mirror)
			)
		)
		(property "Value" ""
			(at 0 0 90)
			(layer "B.Fab")
			(effects
				(font
					(size 1.27 1.27)
				)
				(justify mirror)
			)
		)
		(duplicate_pad_numbers_are_jumpers no)
		(fp_line
			(start 1.524 -0.762)
			(end -1.524 -0.762)
			(stroke
				(width 0.1524)
				(type default)
			)
			(layer "B.SilkS")
		)
		(fp_line
			(start -1.524 -0.762)
			(end -1.524 0.762)
			(stroke
				(width 0.1524)
				(type default)
			)
			(layer "B.SilkS")
		)
		(fp_line
			(start 1.524 0.762)
			(end 1.524 -0.762)
			(stroke
				(width 0.1524)
				(type default)
			)
			(layer "B.SilkS")
		)
		(fp_line
			(start -1.524 0.762)
			(end 1.524 0.762)
			(stroke
				(width 0.1524)
				(type default)
			)
			(layer "B.SilkS")
		)
		(fp_line
			(start 1.1049 -0.724916)
			(end 1.1049 0.724916)
			(stroke
				(width 0.1)
				(type default)
			)
			(layer "B.Fab")
		)
		(fp_line
			(start -1.1049 -0.724916)
			(end 1.1049 -0.724916)
			(stroke
				(width 0.1)
				(type default)
			)
			(layer "B.Fab")
		)
		(fp_line
			(start 1.1049 0.724916)
			(end -1.1049 0.724916)
			(stroke
				(width 0.1)
				(type default)
			)
			(layer "B.Fab")
		)
		(fp_line
			(start -1.1049 0.724916)
			(end -1.1049 -0.724916)
			(stroke
				(width 0.1)
				(type default)
			)
			(layer "B.Fab")
		)
		(pad "1" smd rect
			(at 0.889 0 90)
			(size 1.016 1.27)
			(layers "B.Cu" "B.Mask" "B.Paste")
			(net "SW_P12V_AUX_PVDDCR_CPU1_P0_FLT")
		)
		(pad "2" smd rect
			(at -0.889 0 90)
			(size 1.016 1.27)
			(layers "B.Cu" "B.Mask" "B.Paste")
			(net "GND")
		)
	)
	(footprint ""
		(layer "B.Cu")
		(at 103.759 -418.592 90)
		(property "Reference" "R3034"
			(at 0 0 90)
			(layer "B.SilkS")
			(hide yes)
			(effects
				(font
					(size 1.27 1.27)
				)
				(justify mirror)
			)
		)
		(property "Value" ""
			(at 0 0 90)
			(layer "B.Fab")
			(effects
				(font
					(size 1.27 1.27)
				)
				(justify mirror)
			)
		)
		(duplicate_pad_numbers_are_jumpers no)
		(fp_line
			(start 0.7874 -0.4064)
			(end -0.7874 -0.4064)
			(stroke
				(width 0.1524)
				(type default)
			)
			(layer "B.SilkS")
		)
		(fp_line
			(start -0.7874 -0.4064)
			(end -0.7874 0.4064)
			(stroke
				(width 0.1524)
				(type default)
			)
			(layer "B.SilkS")
		)
		(fp_line
			(start 0.7874 0.4064)
			(end 0.7874 -0.4064)
			(stroke
				(width 0.1524)
				(type default)
			)
			(layer "B.SilkS")
		)
		(fp_line
			(start -0.7874 0.4064)
			(end 0.7874 0.4064)
			(stroke
				(width 0.1524)
				(type default)
			)
			(layer "B.SilkS")
		)
		(fp_line
			(start 0.67945 -0.305054)
			(end 0.12065 -0.305054)
			(stroke
				(width 0.1)
				(type default)
			)
			(layer "B.Fab")
		)
		(fp_line
			(start 0.12065 -0.305054)
			(end 0.12065 -0.2794)
			(stroke
				(width 0.1)
				(type default)
			)
			(layer "B.Fab")
		)
		(fp_line
			(start -0.12065 -0.3048)
			(end -0.67945 -0.3048)
			(stroke
				(width 0.1)
				(type default)
			)
			(layer "B.Fab")
		)
		(fp_line
			(start -0.67945 -0.3048)
			(end -0.67945 0.3048)
			(stroke
				(width 0.1)
				(type default)
			)
			(layer "B.Fab")
		)
		(fp_line
			(start 0.12065 -0.2794)
			(end -0.12065 -0.2794)
			(stroke
				(width 0.1)
				(type default)
			)
			(layer "B.Fab")
		)
		(fp_line
			(start -0.12065 -0.2794)
			(end -0.12065 -0.3048)
			(stroke
				(width 0.1)
				(type default)
			)
			(layer "B.Fab")
		)
		(fp_line
			(start 0.12065 0.2794)
			(end 0.12065 0.3048)
			(stroke
				(width 0.1)
				(type default)
			)
			(layer "B.Fab")
		)
		(fp_line
			(start -0.120396 0.2794)
			(end 0.12065 0.2794)
			(stroke
				(width 0.1)
				(type default)
			)
			(layer "B.Fab")
		)
		(fp_line
			(start 0.67945 0.3048)
			(end 0.67945 -0.305054)
			(stroke
				(width 0.1)
				(type default)
			)
			(layer "B.Fab")
		)
		(fp_line
			(start 0.12065 0.3048)
			(end 0.67945 0.3048)
			(stroke
				(width 0.1)
				(type default)
			)
			(layer "B.Fab")
		)
		(fp_line
			(start -0.120396 0.3048)
			(end -0.120396 0.2794)
			(stroke
				(width 0.1)
				(type default)
			)
			(layer "B.Fab")
		)
		(fp_line
			(start -0.67945 0.3048)
			(end -0.120396 0.3048)
			(stroke
				(width 0.1)
				(type default)
			)
			(layer "B.Fab")
		)
		(pad "1" smd circle
			(at 0.40005 0 270)
			(size 0 0)
			(layers "B.Cu" "B.Mask" "B.Paste")
			(net "P3V3_AUX")
		)
		(pad "2" smd circle
			(at -0.40005 0 270)
			(size 0 0)
			(layers "B.Cu" "B.Mask" "B.Paste")
			(net "FM_SMB_2_ALERT_GPU")
		)
	)
	(footprint ""
		(layer "B.Cu")
		(at 213.616286 -329.201272)
		(property "Reference" "R1240"
			(at 0 0 0)
			(layer "B.SilkS")
			(hide yes)
			(effects
				(font
					(size 1.27 1.27)
				)
				(justify mirror)
			)
		)
		(property "Value" ""
			(at 0 0 0)
			(layer "B.Fab")
			(effects
				(font
					(size 1.27 1.27)
				)
				(justify mirror)
			)
		)
		(duplicate_pad_numbers_are_jumpers no)
		(fp_line
			(start -0.7874 -0.4064)
			(end -0.7874 0.4064)
			(stroke
				(width 0.1524)
				(type default)
			)
			(layer "B.SilkS")
		)
		(fp_line
			(start -0.7874 0.4064)
			(end 0.7874 0.4064)
			(stroke
				(width 0.1524)
				(type default)
			)
			(layer "B.SilkS")
		)
		(fp_line
			(start 0.7874 -0.4064)
			(end -0.7874 -0.4064)
			(stroke
				(width 0.1524)
				(type default)
			)
			(layer "B.SilkS")
		)
		(fp_line
			(start 0.7874 0.4064)
			(end 0.7874 -0.4064)
			(stroke
				(width 0.1524)
				(type default)
			)
			(layer "B.SilkS")
		)
		(fp_line
			(start -0.67945 -0.3048)
			(end -0.67945 0.3048)
			(stroke
				(width 0.1)
				(type default)
			)
			(layer "B.Fab")
		)
		(fp_line
			(start -0.67945 0.3048)
			(end -0.120396 0.3048)
			(stroke
				(width 0.1)
				(type default)
			)
			(layer "B.Fab")
		)
		(fp_line
			(start -0.12065 -0.3048)
			(end -0.67945 -0.3048)
			(stroke
				(width 0.1)
				(type default)
			)
			(layer "B.Fab")
		)
		(fp_line
			(start -0.12065 -0.2794)
			(end -0.12065 -0.3048)
			(stroke
				(width 0.1)
				(type default)
			)
			(layer "B.Fab")
		)
		(fp_line
			(start -0.120396 0.2794)
			(end 0.12065 0.2794)
			(stroke
				(width 0.1)
				(type default)
			)
			(layer "B.Fab")
		)
		(fp_line
			(start -0.120396 0.3048)
			(end -0.120396 0.2794)
			(stroke
				(width 0.1)
				(type default)
			)
			(layer "B.Fab")
		)
		(fp_line
			(start 0.12065 -0.305054)
			(end 0.12065 -0.2794)
			(stroke
				(width 0.1)
				(type default)
			)
			(layer "B.Fab")
		)
		(fp_line
			(start 0.12065 -0.2794)
			(end -0.12065 -0.2794)
			(stroke
				(width 0.1)
				(type default)
			)
			(layer "B.Fab")
		)
		(fp_line
			(start 0.12065 0.2794)
			(end 0.12065 0.3048)
			(stroke
				(width 0.1)
				(type default)
			)
			(layer "B.Fab")
		)
		(fp_line
			(start 0.12065 0.3048)
			(end 0.67945 0.3048)
			(stroke
				(width 0.1)
				(type default)
			)
			(layer "B.Fab")
		)
		(fp_line
			(start 0.67945 -0.305054)
			(end 0.12065 -0.305054)
			(stroke
				(width 0.1)
				(type default)
			)
			(layer "B.Fab")
		)
		(fp_line
			(start 0.67945 0.3048)
			(end 0.67945 -0.305054)
			(stroke
				(width 0.1)
				(type default)
			)
			(layer "B.Fab")
		)
		(pad "1" smd circle
			(at 0.40005 0 180)
			(size 0 0)
			(layers "B.Cu" "B.Mask" "B.Paste")
			(net "ADC128_2_A1")
		)
		(pad "2" smd circle
			(at -0.40005 0 180)
			(size 0 0)
			(layers "B.Cu" "B.Mask" "B.Paste")
			(net "GND")
		)
	)
)
